# T6G (Grand Teton) — schematic netlist excerpt (pin names and nets, part order shuffled) for the footprints in the layout excerpt that follows; sources: Cadence DE-HDL packaged netlist, KiCad conversion of 04192023_DAF0TMB3IC0_F0TG_MB_C_brd_V02_OCP.brd

C129  Q_CAP  0.1UF 10V 10% X7S  pkg C0201  page 323 : A = P1V8_CPU1_RT0_1A ; B = GND
PC866  Q_CAP  22UF 4V 20% X6S  pkg C0805  page 269 : A = P1V8_AUX ; B = GND
R3432  Q_RES  4.7K 5% CHIP  pkg 0402LF  page 126 : A = P3V3_AUX ; B = GPU_FPGA_THERM_OVERT

(kicad_pcb
	(version 20260206)
	(generator "pcbnew")
	(generator_version "10.0")
	(general
		(thickness 1.6)
		(legacy_teardrops no)
	)
	(paper "A4")
	(title_block
		(title "04192023_DAF0TMB3IC0_F0TG_MB_C_brd_V02_OCP.brd")
		(comment 1 "Grand Teton / footprints 8308-8310 of 8354")
	)
	(layers
		(0 "F.Cu" signal "TOP")
		(4 "In1.Cu" signal "GND")
		(6 "In2.Cu" signal "IN1")
		(8 "In3.Cu" signal "GND1")
		(10 "In4.Cu" signal "IN2")
		(12 "In5.Cu" signal "GND2")
		(14 "In6.Cu" signal "IN3")
		(16 "In7.Cu" signal "GND3")
		(18 "In8.Cu" signal "VCC")
		(20 "In9.Cu" signal "VCC1")
		(22 "In10.Cu" signal "GND4")
		(24 "In11.Cu" signal "IN4")
		(26 "In12.Cu" signal "GND5")
		(28 "In13.Cu" signal "IN5")
		(30 "In14.Cu" signal "GND6")
		(32 "In15.Cu" signal "IN6")
		(34 "In16.Cu" signal "GND7")
		(2 "B.Cu" signal "BOTTOM")
		(9 "F.Adhes" user "F.Adhesive")
		(11 "B.Adhes" user "B.Adhesive")
		(13 "F.Paste" user "Package Geometry/Pastemask Top")
		(15 "B.Paste" user "Package Geometry/Pastemask Bottom")
		(5 "F.SilkS" user "Ref Des/Silkscreen Top")
		(7 "B.SilkS" user "Ref Des/Silkscreen Bottom")
		(1 "F.Mask" user "Board Geometry/Soldermask Top")
		(3 "B.Mask" user "Board Geometry/Soldermask Bottom")
		(17 "Dwgs.User" user "User.Drawings")
		(19 "Cmts.User" user "User.Comments")
		(21 "Eco1.User" user "User.Eco1")
		(23 "Eco2.User" user "User.Eco2")
		(25 "Edge.Cuts" user "Board Geometry/Outline")
		(27 "Margin" user)
		(31 "F.CrtYd" user "Package Geometry/Place Bound Top")
		(29 "B.CrtYd" user "Package Geometry/Place Bound Bottom")
		(35 "F.Fab" user "Ref Des/Assembly Top")
		(33 "B.Fab" user "Ref Des/Assembly Bottom")
	)
	(footprint ""
		(layer "B.Cu")
		(at 57.118504 -388.011162 -90)
		(property "Reference" "C129"
			(at 0 0 90)
			(layer "B.SilkS")
			(hide yes)
			(effects
				(font
					(size 1.27 1.27)
				)
				(justify mirror)
			)
		)
		(property "Value" ""
			(at 0 0 90)
			(layer "B.Fab")
			(effects
				(font
					(size 1.27 1.27)
				)
				(justify mirror)
			)
		)
		(duplicate_pad_numbers_are_jumpers no)
		(fp_line
			(start -0.299974 0.150114)
			(end 0.299974 0.150114)
			(stroke
				(width 0.1)
				(type default)
			)
			(layer "B.Fab")
		)
		(fp_line
			(start 0.299974 0.150114)
			(end 0.299974 -0.150114)
			(stroke
				(width 0.1)
				(type default)
			)
			(layer "B.Fab")
		)
		(fp_line
			(start -0.299974 -0.150114)
			(end -0.299974 0.150114)
			(stroke
				(width 0.1)
				(type default)
			)
			(layer "B.Fab")
		)
		(fp_line
			(start 0.299974 -0.150114)
			(end -0.299974 -0.150114)
			(stroke
				(width 0.1)
				(type default)
			)
			(layer "B.Fab")
		)
		(pad "1" smd rect
			(at 0.2667 0 90)
			(size 0.3048 0.381)
			(layers "B.Cu" "B.Mask" "B.Paste")
			(net "P1V8_CPU1_RT0_1A")
		)
		(pad "2" smd rect
			(at -0.2667 0 90)
			(size 0.3048 0.381)
			(layers "B.Cu" "B.Mask" "B.Paste")
			(net "GND")
		)
	)
	(footprint ""
		(layer "B.Cu")
		(at 46.359318 -431.985674 -90)
		(property "Reference" "R3432"
			(at 0 0 90)
			(layer "B.SilkS")
			(hide yes)
			(effects
				(font
					(size 1.27 1.27)
				)
				(justify mirror)
			)
		)
		(property "Value" ""
			(at 0 0 90)
			(layer "B.Fab")
			(effects
				(font
					(size 1.27 1.27)
				)
				(justify mirror)
			)
		)
		(duplicate_pad_numbers_are_jumpers no)
		(fp_line
			(start -0.7874 0.4064)
			(end 0.7874 0.4064)
			(stroke
				(width 0.1524)
				(type default)
			)
			(layer "B.SilkS")
		)
		(fp_line
			(start 0.7874 0.4064)
			(end 0.7874 -0.4064)
			(stroke
				(width 0.1524)
				(type default)
			)
			(layer "B.SilkS")
		)
		(fp_line
			(start -0.7874 -0.4064)
			(end -0.7874 0.4064)
			(stroke
				(width 0.1524)
				(type default)
			)
			(layer "B.SilkS")
		)
		(fp_line
			(start 0.7874 -0.4064)
			(end -0.7874 -0.4064)
			(stroke
				(width 0.1524)
				(type default)
			)
			(layer "B.SilkS")
		)
		(fp_line
			(start -0.67945 0.3048)
			(end -0.120396 0.3048)
			(stroke
				(width 0.1)
				(type default)
			)
			(layer "B.Fab")
		)
		(fp_line
			(start -0.120396 0.3048)
			(end -0.120396 0.2794)
			(stroke
				(width 0.1)
				(type default)
			)
			(layer "B.Fab")
		)
		(fp_line
			(start 0.12065 0.3048)
			(end 0.67945 0.3048)
			(stroke
				(width 0.1)
				(type default)
			)
			(layer "B.Fab")
		)
		(fp_line
			(start 0.67945 0.3048)
			(end 0.67945 -0.305054)
			(stroke
				(width 0.1)
				(type default)
			)
			(layer "B.Fab")
		)
		(fp_line
			(start -0.120396 0.2794)
			(end 0.12065 0.2794)
			(stroke
				(width 0.1)
				(type default)
			)
			(layer "B.Fab")
		)
		(fp_line
			(start 0.12065 0.2794)
			(end 0.12065 0.3048)
			(stroke
				(width 0.1)
				(type default)
			)
			(layer "B.Fab")
		)
		(fp_line
			(start -0.12065 -0.2794)
			(end -0.12065 -0.3048)
			(stroke
				(width 0.1)
				(type default)
			)
			(layer "B.Fab")
		)
		(fp_line
			(start 0.12065 -0.2794)
			(end -0.12065 -0.2794)
			(stroke
				(width 0.1)
				(type default)
			)
			(layer "B.Fab")
		)
		(fp_line
			(start -0.67945 -0.3048)
			(end -0.67945 0.3048)
			(stroke
				(width 0.1)
				(type default)
			)
			(layer "B.Fab")
		)
		(fp_line
			(start -0.12065 -0.3048)
			(end -0.67945 -0.3048)
			(stroke
				(width 0.1)
				(type default)
			)
			(layer "B.Fab")
		)
		(fp_line
			(start 0.12065 -0.305054)
			(end 0.12065 -0.2794)
			(stroke
				(width 0.1)
				(type default)
			)
			(layer "B.Fab")
		)
		(fp_line
			(start 0.67945 -0.305054)
			(end 0.12065 -0.305054)
			(stroke
				(width 0.1)
				(type default)
			)
			(layer "B.Fab")
		)
		(pad "1" smd circle
			(at 0.40005 0 90)
			(size 0 0)
			(layers "B.Cu" "B.Mask" "B.Paste")
			(net "P3V3_AUX")
		)
		(pad "2" smd circle
			(at -0.40005 0 90)
			(size 0 0)
			(layers "B.Cu" "B.Mask" "B.Paste")
			(net "GPU_FPGA_THERM_OVERT")
		)
	)
	(footprint ""
		(layer "B.Cu")
		(at 152.202642 -74.67854)
		(property "Reference" "PC866"
			(at 0 0 0)
			(layer "B.SilkS")
			(hide yes)
			(effects
				(font
					(size 1.27 1.27)
				)
				(justify mirror)
			)
		)
		(property "Value" ""
			(at 0 0 0)
			(layer "B.Fab")
			(effects
				(font
					(size 1.27 1.27)
				)
				(justify mirror)
			)
		)
		(duplicate_pad_numbers_are_jumpers no)
		(fp_line
			(start -1.524 -0.762)
			(end -1.524 0.762)
			(stroke
				(width 0.1524)
				(type default)
			)
			(layer "B.SilkS")
		)
		(fp_line
			(start -1.524 0.762)
			(end 1.524 0.762)
			(stroke
				(width 0.1524)
				(type default)
			)
			(layer "B.SilkS")
		)
		(fp_line
			(start 1.524 -0.762)
			(end -1.524 -0.762)
			(stroke
				(width 0.1524)
				(type default)
			)
			(layer "B.SilkS")
		)
		(fp_line
			(start 1.524 0.762)
			(end 1.524 -0.762)
			(stroke
				(width 0.1524)
				(type default)
			)
			(layer "B.SilkS")
		)
		(fp_line
			(start -1.1049 -0.724916)
			(end 1.1049 -0.724916)
			(stroke
				(width 0.1)
				(type default)
			)
			(layer "B.Fab")
		)
		(fp_line
			(start -1.1049 0.724916)
			(end -1.1049 -0.724916)
			(stroke
				(width 0.1)
				(type default)
			)
			(layer "B.Fab")
		)
		(fp_line
			(start 1.1049 -0.724916)
			(end 1.1049 0.724916)
			(stroke
				(width 0.1)
				(type default)
			)
			(layer "B.Fab")
		)
		(fp_line
			(start 1.1049 0.724916)
			(end -1.1049 0.724916)
			(stroke
				(width 0.1)
				(type default)
			)
			(layer "B.Fab")
		)
		(pad "1" smd rect
			(at 0.889 0)
			(size 1.016 1.27)
			(layers "B.Cu" "B.Mask" "B.Paste")
			(net "P1V8_AUX")
		)
		(pad "2" smd rect
			(at -0.889 0)
			(size 1.016 1.27)
			(layers "B.Cu" "B.Mask" "B.Paste")
			(net "GND")
		)
	)
)
